(kicad_pcb
	(version 20260206)
	(generator "pcbnew")
	(generator_version "10.0")
	(general
		(thickness 1.6)
		(legacy_teardrops no)
	)
	(paper "A4")
	(title_block
		(title "04192023_DAF0TMB3IC0_F0TG_MB_C_brd_V02_OCP.brd")
		(comment 1 "Grand Teton / footprints 5679-5684 of 8354")
	)
	(layers
		(0 "F.Cu" signal "TOP")
		(4 "In1.Cu" signal "GND")
		(6 "In2.Cu" signal "IN1")
		(8 "In3.Cu" signal "GND1")
		(10 "In4.Cu" signal "IN2")
		(12 "In5.Cu" signal "GND2")
		(14 "In6.Cu" signal "IN3")
		(16 "In7.Cu" signal "GND3")
		(18 "In8.Cu" signal "VCC")
		(20 "In9.Cu" signal "VCC1")
		(22 "In10.Cu" signal "GND4")
		(24 "In11.Cu" signal "IN4")
		(26 "In12.Cu" signal "GND5")
		(28 "In13.Cu" signal "IN5")
		(30 "In14.Cu" signal "GND6")
		(32 "In15.Cu" signal "IN6")
		(34 "In16.Cu" signal "GND7")
		(2 "B.Cu" signal "BOTTOM")
		(9 "F.Adhes" user "F.Adhesive")
		(11 "B.Adhes" user "B.Adhesive")
		(13 "F.Paste" user "Package Geometry/Pastemask Top")
		(15 "B.Paste" user "Package Geometry/Pastemask Bottom")
		(5 "F.SilkS" user "Ref Des/Silkscreen Top")
		(7 "B.SilkS" user "Ref Des/Silkscreen Bottom")
		(1 "F.Mask" user "Board Geometry/Soldermask Top")
		(3 "B.Mask" user "Board Geometry/Soldermask Bottom")
		(17 "Dwgs.User" user "User.Drawings")
		(19 "Cmts.User" user "User.Comments")
		(21 "Eco1.User" user "User.Eco1")
		(23 "Eco2.User" user "User.Eco2")
		(25 "Edge.Cuts" user "Board Geometry/Outline")
		(27 "Margin" user)
		(31 "F.CrtYd" user "Package Geometry/Place Bound Top")
		(29 "B.CrtYd" user "Package Geometry/Place Bound Bottom")
		(35 "F.Fab" user "Ref Des/Assembly Top")
		(33 "B.Fab" user "Ref Des/Assembly Bottom")
	)
	(footprint ""
		(layer "B.Cu")
		(at 291.578538 -426.06087 -90)
		(property "Reference" "R2706"
			(at 0 0 90)
			(layer "B.SilkS")
			(hide yes)
			(effects
				(font
					(size 1.27 1.27)
				)
				(justify mirror)
			)
		)
		(property "Value" ""
			(at 0 0 90)
			(layer "B.Fab")
			(effects
				(font
					(size 1.27 1.27)
				)
				(justify mirror)
			)
		)
		(duplicate_pad_numbers_are_jumpers no)
		(fp_line
			(start -0.7874 0.4064)
			(end 0.7874 0.4064)
			(stroke
				(width 0.1524)
				(type default)
			)
			(layer "B.SilkS")
		)
		(fp_line
			(start 0.7874 0.4064)
			(end 0.7874 -0.4064)
			(stroke
				(width 0.1524)
				(type default)
			)
			(layer "B.SilkS")
		)
		(fp_line
			(start -0.7874 -0.4064)
			(end -0.7874 0.4064)
			(stroke
				(width 0.1524)
				(type default)
			)
			(layer "B.SilkS")
		)
		(fp_line
			(start 0.7874 -0.4064)
			(end -0.7874 -0.4064)
			(stroke
				(width 0.1524)
				(type default)
			)
			(layer "B.SilkS")
		)
		(fp_line
			(start -0.67945 0.3048)
			(end -0.120396 0.3048)
			(stroke
				(width 0.1)
				(type default)
			)
			(layer "B.Fab")
		)
		(fp_line
			(start -0.120396 0.3048)
			(end -0.120396 0.2794)
			(stroke
				(width 0.1)
				(type default)
			)
			(layer "B.Fab")
		)
		(fp_line
			(start 0.12065 0.3048)
			(end 0.67945 0.3048)
			(stroke
				(width 0.1)
				(type default)
			)
			(layer "B.Fab")
		)
		(fp_line
			(start 0.67945 0.3048)
			(end 0.67945 -0.305054)
			(stroke
				(width 0.1)
				(type default)
			)
			(layer "B.Fab")
		)
		(fp_line
			(start -0.120396 0.2794)
			(end 0.12065 0.2794)
			(stroke
				(width 0.1)
				(type default)
			)
			(layer "B.Fab")
		)
		(fp_line
			(start 0.12065 0.2794)
			(end 0.12065 0.3048)
			(stroke
				(width 0.1)
				(type default)
			)
			(layer "B.Fab")
		)
		(fp_line
			(start -0.12065 -0.2794)
			(end -0.12065 -0.3048)
			(stroke
				(width 0.1)
				(type default)
			)
			(layer "B.Fab")
		)
		(fp_line
			(start 0.12065 -0.2794)
			(end -0.12065 -0.2794)
			(stroke
				(width 0.1)
				(type default)
			)
			(layer "B.Fab")
		)
		(fp_line
			(start -0.67945 -0.3048)
			(end -0.67945 0.3048)
			(stroke
				(width 0.1)
				(type default)
			)
			(layer "B.Fab")
		)
		(fp_line
			(start -0.12065 -0.3048)
			(end -0.67945 -0.3048)
			(stroke
				(width 0.1)
				(type default)
			)
			(layer "B.Fab")
		)
		(fp_line
			(start 0.12065 -0.305054)
			(end 0.12065 -0.2794)
			(stroke
				(width 0.1)
				(type default)
			)
			(layer "B.Fab")
		)
		(fp_line
			(start 0.67945 -0.305054)
			(end 0.12065 -0.305054)
			(stroke
				(width 0.1)
				(type default)
			)
			(layer "B.Fab")
		)
		(pad "1" smd circle
			(at 0.40005 0 90)
			(size 0 0)
			(layers "B.Cu" "B.Mask" "B.Paste")
			(net "I3C_BMC_SWB_R_SDA")
		)
		(pad "2" smd circle
			(at -0.40005 0 90)
			(size 0 0)
			(layers "B.Cu" "B.Mask" "B.Paste")
			(net "I3C_BMC_SWB_BUF_R_SDA")
		)
	)
	(footprint ""
		(layer "B.Cu")
		(at 408.124914 -389.49503 180)
		(property "Reference" "C7015"
			(at -1.360932 -3.149092 0)
			(unlocked yes)
			(layer "B.SilkS")
			(effects
				(font
					(size 0.7874 0.5842)
					(thickness 0.1524)
				)
				(justify left mirror)
			)
		)
		(property "Value" ""
			(at 0 0 0)
			(layer "B.Fab")
			(effects
				(font
					(size 1.27 1.27)
				)
				(justify mirror)
			)
		)
		(duplicate_pad_numbers_are_jumpers no)
		(fp_line
			(start 4.84378 -2.150618)
			(end 4.842256 2.163064)
			(stroke
				(width 0.1524)
				(type default)
			)
			(layer "B.SilkS")
		)
		(fp_line
			(start 4.84378 -2.150618)
			(end 4.53898 -2.150618)
			(stroke
				(width 0.1524)
				(type default)
			)
			(layer "B.SilkS")
		)
		(fp_line
			(start 4.83108 2.150364)
			(end 4.447794 2.149348)
			(stroke
				(width 0.1524)
				(type default)
			)
			(layer "B.SilkS")
		)
		(fp_line
			(start 4.69138 -2.150618)
			(end 4.692396 2.161032)
			(stroke
				(width 0.1524)
				(type default)
			)
			(layer "B.SilkS")
		)
		(fp_line
			(start 4.53898 2.15011)
			(end 4.53898 -2.15011)
			(stroke
				(width 0.1524)
				(type default)
			)
			(layer "B.SilkS")
		)
		(fp_line
			(start 4.53898 -2.15011)
			(end -4.53898 -2.15011)
			(stroke
				(width 0.1524)
				(type default)
			)
			(layer "B.SilkS")
		)
		(fp_line
			(start 4.53898 -2.150618)
			(end 4.539742 2.152142)
			(stroke
				(width 0.1524)
				(type default)
			)
			(layer "B.SilkS")
		)
		(fp_line
			(start -4.53898 2.15011)
			(end 4.53898 2.15011)
			(stroke
				(width 0.1524)
				(type default)
			)
			(layer "B.SilkS")
		)
		(fp_line
			(start -4.53898 -2.15011)
			(end -4.53898 2.15011)
			(stroke
				(width 0.1524)
				(type default)
			)
			(layer "B.SilkS")
		)
		(fp_line
			(start 3.64998 2.15011)
			(end 3.64998 -2.15011)
			(stroke
				(width 0.1)
				(type default)
			)
			(layer "B.Fab")
		)
		(fp_line
			(start 3.64998 -2.15011)
			(end -3.64998 -2.15011)
			(stroke
				(width 0.1)
				(type default)
			)
			(layer "B.Fab")
		)
		(fp_line
			(start -3.64998 2.15011)
			(end 3.64998 2.15011)
			(stroke
				(width 0.1)
				(type default)
			)
			(layer "B.Fab")
		)
		(fp_line
			(start -3.64998 -2.15011)
			(end -3.64998 2.15011)
			(stroke
				(width 0.1)
				(type default)
			)
			(layer "B.Fab")
		)
		(fp_text user "+"
			(at 4.444492 -3.049778 180)
			(unlocked yes)
			(layer "B.SilkS")
			(effects
				(font
					(size 1.905 1.4224)
					(thickness 0.1524)
				)
				(justify left mirror)
			)
		)
		(fp_text user "-"
			(at -2.781554 -2.878328 180)
			(unlocked yes)
			(layer "B.SilkS")
			(effects
				(font
					(size 1.905 1.4224)
					(thickness 0.1524)
				)
				(justify left mirror)
			)
		)
		(fp_text user "+"
			(at 6.214872 -0.337058 180)
			(unlocked yes)
			(layer "B.Fab")
			(effects
				(font
					(size 1.905 1.4224)
					(thickness 0.1524)
				)
				(justify left mirror)
			)
		)
		(fp_text user "-"
			(at -4.313174 -0.094488 180)
			(unlocked yes)
			(layer "B.Fab")
			(effects
				(font
					(size 1.905 1.4224)
					(thickness 0.1524)
				)
				(justify left mirror)
			)
		)
		(pad "1" smd rect
			(at 3.199892 0)
			(size 2.413 2.8194)
			(layers "B.Cu" "B.Mask" "B.Paste")
			(net "P0V9_CPU0_RT2_2A")
		)
		(pad "2" smd rect
			(at -3.199892 0)
			(size 2.413 2.8194)
			(layers "B.Cu" "B.Mask" "B.Paste")
			(net "GND")
		)
	)
	(footprint ""
		(layer "B.Cu")
		(at 504.058428 7.571994 90)
		(property "Reference" "X8025"
			(at 0.93726 -1.53035 270)
			(unlocked yes)
			(layer "B.SilkS")
			(effects
				(font
					(size 0.7874 0.5842)
					(thickness 0.1524)
				)
				(justify left mirror)
			)
		)
		(property "Value" ""
			(at 0 0 90)
			(layer "B.Fab")
			(effects
				(font
					(size 1.27 1.27)
				)
				(justify mirror)
			)
		)
		(property "Device Type" "TP_TDR_4P_FTS_TH-TP_TDR_4P_DIP,EMPTY,TP15"
			(at -1.30175 1.27 0)
			(unlocked yes)
			(layer "B.Fab")
			(hide yes)
			(effects
				(font
					(size 0.635 0.4064)
					(thickness 0.1524)
				)
				(justify mirror)
			)
		)
		(property "User Part Number" "N_A"
			(at -1.30175 1.27 0)
			(unlocked yes)
			(layer "Cmts.User")
			(hide yes)
			(effects
				(font
					(size 0.635 0.4064)
					(thickness 0.1524)
				)
				(justify mirror)
			)
		)
		(duplicate_pad_numbers_are_jumpers no)
		(fp_line
			(start 0 -1.27)
			(end 0 -0.635)
			(stroke
				(width 0.1524)
				(type default)
			)
			(layer "B.SilkS")
		)
		(fp_line
			(start -2.54 -1.27)
			(end 0 -1.27)
			(stroke
				(width 0.1524)
				(type default)
			)
			(layer "B.SilkS")
		)
		(fp_line
			(start -2.54 -1.1303)
			(end -2.54 -1.27)
			(stroke
				(width 0.1524)
				(type default)
			)
			(layer "B.SilkS")
		)
		(fp_line
			(start 0 0.635)
			(end 0 1.905)
			(stroke
				(width 0.1524)
				(type default)
			)
			(layer "B.SilkS")
		)
		(fp_line
			(start -2.54 1.4097)
			(end -2.54 1.1303)
			(stroke
				(width 0.1524)
				(type default)
			)
			(layer "B.SilkS")
		)
		(fp_line
			(start 0 3.175)
			(end 0 3.81)
			(stroke
				(width 0.1524)
				(type default)
			)
			(layer "B.SilkS")
		)
		(fp_line
			(start 0 3.81)
			(end -2.54 3.81)
			(stroke
				(width 0.1524)
				(type default)
			)
			(layer "B.SilkS")
		)
		(fp_line
			(start -2.54 3.81)
			(end -2.54 3.6703)
			(stroke
				(width 0.1524)
				(type default)
			)
			(layer "B.SilkS")
		)
		(fp_poly
			(pts
				(xy 0.761746 0) (xy 2.285746 -0.762) (xy 2.285746 0.762)
			)
			(stroke
				(width 0)
				(type default)
			)
			(fill yes)
			(layer "B.SilkS")
		)
		(fp_line
			(start 0 -1.27)
			(end 0 3.81)
			(stroke
				(width 0.1)
				(type default)
			)
			(layer "B.Fab")
		)
		(fp_line
			(start -2.54 -1.27)
			(end 0 -1.27)
			(stroke
				(width 0.1)
				(type default)
			)
			(layer "B.Fab")
		)
		(fp_line
			(start 0 3.81)
			(end -2.54 3.81)
			(stroke
				(width 0.1)
				(type default)
			)
			(layer "B.Fab")
		)
		(fp_line
			(start -2.54 3.81)
			(end -2.54 -1.27)
			(stroke
				(width 0.1)
				(type default)
			)
			(layer "B.Fab")
		)
		(fp_poly
			(pts
				(xy 0.761746 0) (xy 2.285746 -0.762) (xy 2.285746 0.762)
			)
			(stroke
				(width 0)
				(type default)
			)
			(fill yes)
			(layer "B.Fab")
		)
		(pad "1" thru_hole circle
			(at 0 0 270)
			(size 1.0033 1.0033)
			(drill 0.249936)
			(layers "*.Cu" "*.Mask")
			(remove_unused_layers no)
			(net "TDR_DIFF_85_IN5_DP")
			(clearance 0.10795)
			(padstack
				(mode front_inner_back)
				(layer "Inner"
					(shape circle)
					(size 0.8001 0.8001)
					(clearance 0.1524)
				)
				(layer "B.Cu"
					(shape circle)
					(size 1.0033 1.0033)
					(thermal_gap 0.10795)
					(clearance 0.10795)
				)
			)
		)
		(pad "2" thru_hole circle
			(at -2.54 0 270)
			(size 1.9939 1.9939)
			(drill 0.249936)
			(layers "*.Cu" "*.Mask")
			(remove_unused_layers no)
			(net "T1_GND")
			(clearance 0.10795)
			(padstack
				(mode front_inner_back)
				(layer "Inner"
					(shape circle)
					(size 0.8001 0.8001)
					(clearance 0.1524)
				)
				(layer "B.Cu"
					(shape circle)
					(size 1.9939 1.9939)
					(thermal_gap 0.10795)
					(clearance 0.10795)
				)
			)
		)
		(pad "3" thru_hole circle
			(at -2.54 2.54 270)
			(size 1.9939 1.9939)
			(drill 0.249936)
			(layers "*.Cu" "*.Mask")
			(remove_unused_layers no)
			(net "T1_GND")
			(clearance 0.10795)
			(padstack
				(mode front_inner_back)
				(layer "Inner"
					(shape circle)
					(size 0.8001 0.8001)
					(clearance 0.1524)
				)
				(layer "B.Cu"
					(shape circle)
					(size 1.9939 1.9939)
					(thermal_gap 0.10795)
					(clearance 0.10795)
				)
			)
		)
		(pad "4" thru_hole circle
			(at 0 2.54 270)
			(size 1.0033 1.0033)
			(drill 0.249936)
			(layers "*.Cu" "*.Mask")
			(remove_unused_layers no)
			(net "TDR_DIFF_85_IN5_DN")
			(clearance 0.10795)
			(padstack
				(mode front_inner_back)
				(layer "Inner"
					(shape circle)
					(size 0.8001 0.8001)
					(clearance 0.1524)
				)
				(layer "B.Cu"
					(shape circle)
					(size 1.0033 1.0033)
					(thermal_gap 0.10795)
					(clearance 0.10795)
				)
			)
		)
	)
	(footprint ""
		(layer "B.Cu")
		(at 102.253034 -254.504952 -60)
		(property "Reference" "C2421"
			(at 0 0 120)
			(layer "B.SilkS")
			(hide yes)
			(effects
				(font
					(size 1.27 1.27)
				)
				(justify mirror)
			)
		)
		(property "Value" ""
			(at 0 0 120)
			(layer "B.Fab")
			(effects
				(font
					(size 1.27 1.27)
				)
				(justify mirror)
			)
		)
		(duplicate_pad_numbers_are_jumpers no)
		(fp_line
			(start -0.787516 0.406438)
			(end 0.787425 0.40652)
			(stroke
				(width 0.1524)
				(type default)
			)
			(layer "B.SilkS")
		)
		(fp_line
			(start -0.787425 -0.40652)
			(end -0.787516 0.406438)
			(stroke
				(width 0.1524)
				(type default)
			)
			(layer "B.SilkS")
		)
		(fp_line
			(start 0.787425 0.40652)
			(end 0.787516 -0.406438)
			(stroke
				(width 0.1524)
				(type default)
			)
			(layer "B.SilkS")
		)
		(fp_line
			(start 0.787516 -0.406438)
			(end -0.787425 -0.40652)
			(stroke
				(width 0.1524)
				(type default)
			)
			(layer "B.SilkS")
		)
		(fp_line
			(start -0.679568 0.304811)
			(end -0.120258 0.304812)
			(stroke
				(width 0.1)
				(type default)
			)
			(layer "B.Fab")
		)
		(fp_line
			(start -0.120258 0.304812)
			(end -0.120334 0.279545)
			(stroke
				(width 0.1)
				(type default)
			)
			(layer "B.Fab")
		)
		(fp_line
			(start -0.120334 0.279545)
			(end 0.120587 0.279326)
			(stroke
				(width 0.1)
				(type default)
			)
			(layer "B.Fab")
		)
		(fp_line
			(start 0.120536 0.304813)
			(end 0.6795 0.304908)
			(stroke
				(width 0.1)
				(type default)
			)
			(layer "B.Fab")
		)
		(fp_line
			(start 0.120587 0.279326)
			(end 0.120536 0.304813)
			(stroke
				(width 0.1)
				(type default)
			)
			(layer "B.Fab")
		)
		(fp_line
			(start -0.6795 -0.304908)
			(end -0.679568 0.304811)
			(stroke
				(width 0.1)
				(type default)
			)
			(layer "B.Fab")
		)
		(fp_line
			(start 0.6795 0.304908)
			(end 0.679475 -0.305158)
			(stroke
				(width 0.1)
				(type default)
			)
			(layer "B.Fab")
		)
		(fp_line
			(start -0.120587 -0.279326)
			(end -0.120536 -0.304813)
			(stroke
				(width 0.1)
				(type default)
			)
			(layer "B.Fab")
		)
		(fp_line
			(start -0.120536 -0.304813)
			(end -0.6795 -0.304908)
			(stroke
				(width 0.1)
				(type default)
			)
			(layer "B.Fab")
		)
		(fp_line
			(start 0.120554 -0.279418)
			(end -0.120587 -0.279326)
			(stroke
				(width 0.1)
				(type default)
			)
			(layer "B.Fab")
		)
		(fp_line
			(start 0.120732 -0.305125)
			(end 0.120554 -0.279418)
			(stroke
				(width 0.1)
				(type default)
			)
			(layer "B.Fab")
		)
		(fp_line
			(start 0.679475 -0.305158)
			(end 0.120732 -0.305125)
			(stroke
				(width 0.1)
				(type default)
			)
			(layer "B.Fab")
		)
		(pad "1" smd circle
			(at 0.40005 0 120)
			(size 0 0)
			(layers "B.Cu" "B.Mask" "B.Paste")
			(net "PVDDCR_SOC_P1")
		)
		(pad "2" smd circle
			(at -0.40005 0 120)
			(size 0 0)
			(layers "B.Cu" "B.Mask" "B.Paste")
			(net "GND")
		)
	)
	(footprint ""
		(layer "B.Cu")
		(at 99.100386 -255.845564 180)
		(property "Reference" "C2293"
			(at 0 0 0)
			(layer "B.SilkS")
			(hide yes)
			(effects
				(font
					(size 1.27 1.27)
				)
				(justify mirror)
			)
		)
		(property "Value" ""
			(at 0 0 0)
			(layer "B.Fab")
			(effects
				(font
					(size 1.27 1.27)
				)
				(justify mirror)
			)
		)
		(duplicate_pad_numbers_are_jumpers no)
		(fp_line
			(start 0.7874 0.4064)
			(end 0.7874 -0.4064)
			(stroke
				(width 0.1524)
				(type default)
			)
			(layer "B.SilkS")
		)
		(fp_line
			(start 0.7874 -0.4064)
			(end -0.7874 -0.4064)
			(stroke
				(width 0.1524)
				(type default)
			)
			(layer "B.SilkS")
		)
		(fp_line
			(start -0.7874 0.4064)
			(end 0.7874 0.4064)
			(stroke
				(width 0.1524)
				(type default)
			)
			(layer "B.SilkS")
		)
		(fp_line
			(start -0.7874 -0.4064)
			(end -0.7874 0.4064)
			(stroke
				(width 0.1524)
				(type default)
			)
			(layer "B.SilkS")
		)
		(fp_line
			(start 0.67945 0.3048)
			(end 0.67945 -0.305054)
			(stroke
				(width 0.1)
				(type default)
			)
			(layer "B.Fab")
		)
		(fp_line
			(start 0.67945 -0.305054)
			(end 0.12065 -0.305054)
			(stroke
				(width 0.1)
				(type default)
			)
			(layer "B.Fab")
		)
		(fp_line
			(start 0.12065 0.3048)
			(end 0.67945 0.3048)
			(stroke
				(width 0.1)
				(type default)
			)
			(layer "B.Fab")
		)
		(fp_line
			(start 0.12065 0.2794)
			(end 0.12065 0.3048)
			(stroke
				(width 0.1)
				(type default)
			)
			(layer "B.Fab")
		)
		(fp_line
			(start 0.12065 -0.2794)
			(end -0.12065 -0.2794)
			(stroke
				(width 0.1)
				(type default)
			)
			(layer "B.Fab")
		)
		(fp_line
			(start 0.12065 -0.305054)
			(end 0.12065 -0.2794)
			(stroke
				(width 0.1)
				(type default)
			)
			(layer "B.Fab")
		)
		(fp_line
			(start -0.120396 0.3048)
			(end -0.120396 0.2794)
			(stroke
				(width 0.1)
				(type default)
			)
			(layer "B.Fab")
		)
		(fp_line
			(start -0.120396 0.2794)
			(end 0.12065 0.2794)
			(stroke
				(width 0.1)
				(type default)
			)
			(layer "B.Fab")
		)
		(fp_line
			(start -0.12065 -0.2794)
			(end -0.12065 -0.3048)
			(stroke
				(width 0.1)
				(type default)
			)
			(layer "B.Fab")
		)
		(fp_line
			(start -0.12065 -0.3048)
			(end -0.67945 -0.3048)
			(stroke
				(width 0.1)
				(type default)
			)
			(layer "B.Fab")
		)
		(fp_line
			(start -0.67945 0.3048)
			(end -0.120396 0.3048)
			(stroke
				(width 0.1)
				(type default)
			)
			(layer "B.Fab")
		)
		(fp_line
			(start -0.67945 -0.3048)
			(end -0.67945 0.3048)
			(stroke
				(width 0.1)
				(type default)
			)
			(layer "B.Fab")
		)
		(pad "1" smd circle
			(at 0.40005 0)
			(size 0 0)
			(layers "B.Cu" "B.Mask" "B.Paste")
			(net "PVDD18_S5_P1")
		)
		(pad "2" smd circle
			(at -0.40005 0)
			(size 0 0)
			(layers "B.Cu" "B.Mask" "B.Paste")
			(net "GND")
		)
	)
	(footprint ""
		(layer "B.Cu")
		(at 333.627476 -396.991078 90)
		(property "Reference" "C616"
			(at 0 0 90)
			(layer "B.SilkS")
			(hide yes)
			(effects
				(font
					(size 1.27 1.27)
				)
				(justify mirror)
			)
		)
		(property "Value" ""
			(at 0 0 90)
			(layer "B.Fab")
			(effects
				(font
					(size 1.27 1.27)
				)
				(justify mirror)
			)
		)
		(duplicate_pad_numbers_are_jumpers no)
		(fp_line
			(start 0.299974 -0.150114)
			(end -0.299974 -0.150114)
			(stroke
				(width 0.1)
				(type default)
			)
			(layer "B.Fab")
		)
		(fp_line
			(start -0.299974 -0.150114)
			(end -0.299974 0.150114)
			(stroke
				(width 0.1)
				(type default)
			)
			(layer "B.Fab")
		)
		(fp_line
			(start 0.299974 0.150114)
			(end 0.299974 -0.150114)
			(stroke
				(width 0.1)
				(type default)
			)
			(layer "B.Fab")
		)
		(fp_line
			(start -0.299974 0.150114)
			(end 0.299974 0.150114)
			(stroke
				(width 0.1)
				(type default)
			)
			(layer "B.Fab")
		)
		(pad "1" smd rect
			(at 0.2667 0 270)
			(size 0.3048 0.381)
			(layers "B.Cu" "B.Mask" "B.Paste")
			(net "P0V9_CPU0_RT1_2A")
		)
		(pad "2" smd rect
			(at -0.2667 0 270)
			(size 0.3048 0.381)
			(layers "B.Cu" "B.Mask" "B.Paste")
			(net "GND")
		)
	)
)
